(kicad_pcb
	(version 20260206)
	(generator "pcbnew")
	(generator_version "10.0")
	(general
		(thickness 1.6)
		(legacy_teardrops no)
	)
	(paper "A4")
	(title_block
		(title "dpb — 14545-sa.0730WZS0815.brd")
		(comment 1 "Honey Badger (Wiwynn) / footprints 80-87 of 1066")
	)
	(layers
		(0 "F.Cu" signal "TOP")
		(4 "In1.Cu" signal "L2GND")
		(6 "In2.Cu" signal "L3")
		(8 "In3.Cu" signal "L4VCC")
		(10 "In4.Cu" signal "L5VCC")
		(12 "In5.Cu" signal "L6")
		(14 "In6.Cu" signal "L7GND")
		(2 "B.Cu" signal "BOTTOM")
		(9 "F.Adhes" user "F.Adhesive")
		(11 "B.Adhes" user "B.Adhesive")
		(13 "F.Paste" user "Package Geometry/Pastemask Top")
		(15 "B.Paste" user "Package Geometry/Pastemask Bottom")
		(5 "F.SilkS" user "Ref Des/Silkscreen Top")
		(7 "B.SilkS" user "Ref Des/Silkscreen Bottom")
		(1 "F.Mask" user "Board Geometry/Soldermask Top")
		(3 "B.Mask" user "Board Geometry/Soldermask Bottom")
		(17 "Dwgs.User" user "User.Drawings")
		(19 "Cmts.User" user "User.Comments")
		(21 "Eco1.User" user "User.Eco1")
		(23 "Eco2.User" user "User.Eco2")
		(25 "Edge.Cuts" user "Board Geometry/Outline")
		(27 "Margin" user)
		(31 "F.CrtYd" user "Package Geometry/Place Bound Top")
		(29 "B.CrtYd" user "Package Geometry/Place Bound Bottom")
		(35 "F.Fab" user "Ref Des/Assembly Top")
		(33 "B.Fab" user "Ref Des/Assembly Bottom")
	)
	(footprint ""
		(layer "F.Cu")
		(at 83.185 -89.662)
		(property "Reference" "C373"
			(at 0 0 0)
			(layer "F.SilkS")
			(hide yes)
			(effects
				(font
					(size 1.27 1.27)
				)
			)
		)
		(property "Value" "SCD033U25V2KX-GP"
			(at 1.1811 -2.7051 0)
			(unlocked yes)
			(layer "F.Fab")
			(hide yes)
			(effects
				(font
					(size 1.016 1.016)
					(thickness 0.1524)
				)
			)
		)
		(property "Device Type" "C402H22"
			(at 1.1811 -4.2291 0)
			(unlocked yes)
			(layer "F.Fab")
			(hide yes)
			(effects
				(font
					(size 1.016 1.016)
					(thickness 0.1524)
				)
			)
		)
		(duplicate_pad_numbers_are_jumpers no)
		(fp_rect
			(start -0.4318 0.9525)
			(end 0.4318 -0.9525)
			(stroke
				(width 0)
				(type default)
			)
			(fill no)
			(layer "F.CrtYd")
		)
		(fp_rect
			(start -0.4318 0.9525)
			(end 0.4318 -0.9525)
			(stroke
				(width 0)
				(type default)
			)
			(fill no)
			(layer "F.Fab")
		)
		(pad "1" smd custom
			(at 0 -0.4445)
			(size 0.1524 0.1524)
			(layers "F.Cu" "F.Mask" "F.Paste")
			(net "SW_HDD9_P")
			(options
				(clearance outline)
				(anchor circle)
			)
			(primitives
				(gr_poly
					(pts
						(arc
							(start 0.3048 -0.2032)
							(mid 0.275042 -0.275042)
							(end 0.2032 -0.3048)
						)
						(arc
							(start -0.2032 -0.3048)
							(mid -0.275042 -0.275042)
							(end -0.3048 -0.2032)
						)
						(arc
							(start -0.3048 0.2032)
							(mid -0.275042 0.275042)
							(end -0.2032 0.3048)
						)
						(arc
							(start 0.2032 0.3048)
							(mid 0.275042 0.275042)
							(end 0.3048 0.2032)
						)
					)
					(width 0)
					(fill yes)
				)
			)
		)
		(pad "2" smd custom
			(at 0 0.4445)
			(size 0.1524 0.1524)
			(layers "F.Cu" "F.Mask" "F.Paste")
			(net "GND")
			(options
				(clearance outline)
				(anchor circle)
			)
			(primitives
				(gr_poly
					(pts
						(arc
							(start 0.3048 -0.2032)
							(mid 0.275042 -0.275042)
							(end 0.2032 -0.3048)
						)
						(arc
							(start -0.2032 -0.3048)
							(mid -0.275042 -0.275042)
							(end -0.3048 -0.2032)
						)
						(arc
							(start -0.3048 0.2032)
							(mid -0.275042 0.275042)
							(end -0.2032 0.3048)
						)
						(arc
							(start 0.2032 0.3048)
							(mid 0.275042 0.275042)
							(end 0.3048 0.2032)
						)
					)
					(width 0)
					(fill yes)
				)
			)
		)
	)
	(footprint ""
		(layer "F.Cu")
		(at 26.796746 -304.828702 180)
		(property "Reference" "R467"
			(at 0 0 180)
			(layer "F.SilkS")
			(hide yes)
			(effects
				(font
					(size 1.27 1.27)
				)
			)
		)
		(property "Value" "4K7R2J-2-GP"
			(at 0.064008 -3.993896 180)
			(unlocked yes)
			(layer "F.Fab")
			(hide yes)
			(effects
				(font
					(size 1.016 1.016)
					(thickness 0.1524)
				)
			)
		)
		(property "Device Type" "R402H16"
			(at 0.064008 -5.517896 180)
			(unlocked yes)
			(layer "F.Fab")
			(hide yes)
			(effects
				(font
					(size 1.016 1.016)
					(thickness 0.1524)
				)
			)
		)
		(duplicate_pad_numbers_are_jumpers no)
		(fp_line
			(start 0.508 -0.9398)
			(end -0.508 -0.9398)
			(stroke
				(width 0.1524)
				(type default)
			)
			(layer "F.SilkS")
		)
		(fp_line
			(start -0.508 -0.9398)
			(end -0.508 0.9398)
			(stroke
				(width 0.1524)
				(type default)
			)
			(layer "F.SilkS")
		)
		(fp_rect
			(start -0.508 0.9398)
			(end 0.508 -0.9398)
			(stroke
				(width 0)
				(type default)
			)
			(fill no)
			(layer "F.CrtYd")
		)
		(fp_rect
			(start -0.508 0.9398)
			(end 0.508 -0.9398)
			(stroke
				(width 0)
				(type default)
			)
			(fill no)
			(layer "F.Fab")
		)
		(pad "1" smd custom
			(at 0 -0.4445 180)
			(size 0.1397 0.1397)
			(layers "F.Cu" "F.Mask" "F.Paste")
			(net "P3V3")
			(options
				(clearance outline)
				(anchor circle)
			)
			(primitives
				(gr_poly
					(pts
						(arc
							(start -0.1778 -0.2794)
							(mid -0.249642 -0.249642)
							(end -0.2794 -0.1778)
						)
						(arc
							(start -0.2794 0.1778)
							(mid -0.249642 0.249642)
							(end -0.1778 0.2794)
						)
						(arc
							(start 0.1778 0.2794)
							(mid 0.249642 0.249642)
							(end 0.2794 0.1778)
						)
						(arc
							(start 0.2794 -0.1778)
							(mid 0.249642 -0.249642)
							(end 0.1778 -0.2794)
						)
					)
					(width 0)
					(fill yes)
				)
			)
		)
		(pad "2" smd custom
			(at 0 0.4445 180)
			(size 0.1397 0.1397)
			(layers "F.Cu" "F.Mask" "F.Paste")
			(net "SAS_EXP_B_PWR11")
			(options
				(clearance outline)
				(anchor circle)
			)
			(primitives
				(gr_poly
					(pts
						(arc
							(start -0.1778 -0.2794)
							(mid -0.249642 -0.249642)
							(end -0.2794 -0.1778)
						)
						(arc
							(start -0.2794 0.1778)
							(mid -0.249642 0.249642)
							(end -0.1778 0.2794)
						)
						(arc
							(start 0.1778 0.2794)
							(mid 0.249642 0.249642)
							(end 0.2794 0.1778)
						)
						(arc
							(start 0.2794 -0.1778)
							(mid 0.249642 -0.249642)
							(end 0.1778 -0.2794)
						)
					)
					(width 0)
					(fill yes)
				)
			)
		)
	)
	(footprint ""
		(layer "F.Cu")
		(at 50.095404 -22.968712 90)
		(property "Reference" "TP23"
			(at 0 0 90)
			(layer "F.SilkS")
			(hide yes)
			(effects
				(font
					(size 1.27 1.27)
				)
			)
		)
		(property "Value" "TPAD32-GP"
			(at 0 -3.166364 90)
			(unlocked yes)
			(layer "F.Fab")
			(hide yes)
			(effects
				(font
					(size 1.016 1.016)
					(thickness 0.1524)
				)
			)
		)
		(property "Device Type" "TPAD32"
			(at 0 -4.690618 90)
			(unlocked yes)
			(layer "F.Fab")
			(hide yes)
			(effects
				(font
					(size 1.016 1.016)
					(thickness 0.1524)
				)
			)
		)
		(duplicate_pad_numbers_are_jumpers no)
		(fp_poly
			(pts
				(arc
					(start 0 0.4064)
					(mid 0 -0.4064)
					(end 0 0.4064)
				)
			)
			(stroke
				(width 0)
				(type default)
			)
			(fill no)
			(layer "F.CrtYd")
		)
		(fp_poly
			(pts
				(arc
					(start 0 0.7112)
					(mid 0 -0.7112)
					(end 0 0.7112)
				)
			)
			(stroke
				(width 0)
				(type default)
			)
			(fill no)
			(layer "F.Fab")
		)
		(pad "1" smd circle
			(at 0 0 90)
			(size 0.8128 0.8128)
			(layers "F.Cu" "F.Mask" "F.Paste")
			(net "P5VB_PGD")
		)
	)
	(footprint ""
		(layer "F.Cu")
		(at 219.6846 -86.8934 180)
		(property "Reference" "C179"
			(at 0 0 180)
			(layer "F.SilkS")
			(hide yes)
			(effects
				(font
					(size 1.27 1.27)
				)
			)
		)
		(property "Value" "SC1U25V3KX-1-GP"
			(at 0 -2.8194 180)
			(unlocked yes)
			(layer "F.Fab")
			(hide yes)
			(effects
				(font
					(size 1.016 1.016)
					(thickness 0.1524)
				)
			)
		)
		(property "Device Type" "C603H36"
			(at 0 -4.3434 180)
			(unlocked yes)
			(layer "F.Fab")
			(hide yes)
			(effects
				(font
					(size 1.016 1.016)
					(thickness 0.1524)
				)
			)
		)
		(duplicate_pad_numbers_are_jumpers no)
		(fp_line
			(start 0.508 0)
			(end -0.508 0)
			(stroke
				(width 0.2032)
				(type default)
			)
			(layer "F.SilkS")
		)
		(fp_rect
			(start -0.5842 1.3335)
			(end 0.5842 -1.3335)
			(stroke
				(width 0)
				(type default)
			)
			(fill no)
			(layer "F.CrtYd")
		)
		(fp_rect
			(start -0.5842 1.3335)
			(end 0.5842 -1.3335)
			(stroke
				(width 0)
				(type default)
			)
			(fill no)
			(layer "F.Fab")
		)
		(pad "1" smd custom
			(at 0 -0.762 180)
			(size 0.2159 0.2159)
			(layers "F.Cu" "F.Mask" "F.Paste")
			(net "P12V_HDD4")
			(options
				(clearance outline)
				(anchor circle)
			)
			(primitives
				(gr_poly
					(pts
						(arc
							(start -0.3302 -0.4318)
							(mid -0.402042 -0.402042)
							(end -0.4318 -0.3302)
						)
						(arc
							(start -0.4318 0.3302)
							(mid -0.402042 0.402042)
							(end -0.3302 0.4318)
						)
						(arc
							(start 0.3302 0.4318)
							(mid 0.402042 0.402042)
							(end 0.4318 0.3302)
						)
						(arc
							(start 0.4318 -0.3302)
							(mid 0.402042 -0.402042)
							(end 0.3302 -0.4318)
						)
					)
					(width 0)
					(fill yes)
				)
			)
		)
		(pad "2" smd custom
			(at 0 0.762 180)
			(size 0.2159 0.2159)
			(layers "F.Cu" "F.Mask" "F.Paste")
			(net "GND")
			(options
				(clearance outline)
				(anchor circle)
			)
			(primitives
				(gr_poly
					(pts
						(arc
							(start -0.3302 -0.4318)
							(mid -0.402042 -0.402042)
							(end -0.4318 -0.3302)
						)
						(arc
							(start -0.4318 0.3302)
							(mid -0.402042 0.402042)
							(end -0.3302 0.4318)
						)
						(arc
							(start 0.3302 0.4318)
							(mid 0.402042 0.402042)
							(end 0.4318 0.3302)
						)
						(arc
							(start 0.4318 -0.3302)
							(mid 0.402042 -0.402042)
							(end 0.3302 -0.4318)
						)
					)
					(width 0)
					(fill yes)
				)
			)
		)
	)
	(footprint ""
		(layer "F.Cu")
		(at 211.835746 -52.4637)
		(property "Reference" "R330"
			(at 0 0 0)
			(layer "F.SilkS")
			(hide yes)
			(effects
				(font
					(size 1.27 1.27)
				)
			)
		)
		(property "Value" "0R2J-2-GP"
			(at 0.064008 -3.993896 0)
			(unlocked yes)
			(layer "F.Fab")
			(hide yes)
			(effects
				(font
					(size 1.016 1.016)
					(thickness 0.1524)
				)
			)
		)
		(property "Device Type" "R402H16"
			(at 0.064008 -5.517896 0)
			(unlocked yes)
			(layer "F.Fab")
			(hide yes)
			(effects
				(font
					(size 1.016 1.016)
					(thickness 0.1524)
				)
			)
		)
		(duplicate_pad_numbers_are_jumpers no)
		(fp_line
			(start -0.508 -0.9398)
			(end -0.508 0.9398)
			(stroke
				(width 0.1524)
				(type default)
			)
			(layer "F.SilkS")
		)
		(fp_line
			(start 0.508 -0.9398)
			(end -0.508 -0.9398)
			(stroke
				(width 0.1524)
				(type default)
			)
			(layer "F.SilkS")
		)
		(fp_rect
			(start -0.508 0.9398)
			(end 0.508 -0.9398)
			(stroke
				(width 0)
				(type default)
			)
			(fill no)
			(layer "F.CrtYd")
		)
		(fp_rect
			(start -0.508 0.9398)
			(end 0.508 -0.9398)
			(stroke
				(width 0)
				(type default)
			)
			(fill no)
			(layer "F.Fab")
		)
		(pad "1" smd custom
			(at 0 -0.4445)
			(size 0.1397 0.1397)
			(layers "F.Cu" "F.Mask" "F.Paste")
			(net "I2C_B_SDA")
			(options
				(clearance outline)
				(anchor circle)
			)
			(primitives
				(gr_poly
					(pts
						(arc
							(start -0.1778 -0.2794)
							(mid -0.249642 -0.249642)
							(end -0.2794 -0.1778)
						)
						(arc
							(start -0.2794 0.1778)
							(mid -0.249642 0.249642)
							(end -0.1778 0.2794)
						)
						(arc
							(start 0.1778 0.2794)
							(mid 0.249642 0.249642)
							(end 0.2794 0.1778)
						)
						(arc
							(start 0.2794 -0.1778)
							(mid 0.249642 -0.249642)
							(end 0.1778 -0.2794)
						)
					)
					(width 0)
					(fill yes)
				)
			)
		)
		(pad "2" smd custom
			(at 0 0.4445)
			(size 0.1397 0.1397)
			(layers "F.Cu" "F.Mask" "F.Paste")
			(net "TMP4_SDA")
			(options
				(clearance outline)
				(anchor circle)
			)
			(primitives
				(gr_poly
					(pts
						(arc
							(start -0.1778 -0.2794)
							(mid -0.249642 -0.249642)
							(end -0.2794 -0.1778)
						)
						(arc
							(start -0.2794 0.1778)
							(mid -0.249642 0.249642)
							(end -0.1778 0.2794)
						)
						(arc
							(start 0.1778 0.2794)
							(mid 0.249642 0.249642)
							(end 0.2794 0.1778)
						)
						(arc
							(start 0.2794 -0.1778)
							(mid 0.249642 -0.249642)
							(end 0.1778 -0.2794)
						)
					)
					(width 0)
					(fill yes)
				)
			)
		)
	)
	(footprint ""
		(layer "F.Cu")
		(at 78.358746 -399.5547 90)
		(property "Reference" "R194"
			(at 0 0 90)
			(layer "F.SilkS")
			(hide yes)
			(effects
				(font
					(size 1.27 1.27)
				)
			)
		)
		(property "Value" "200KR2F-L-GP"
			(at 0.064008 -3.993896 90)
			(unlocked yes)
			(layer "F.Fab")
			(hide yes)
			(effects
				(font
					(size 1.016 1.016)
					(thickness 0.1524)
				)
			)
		)
		(property "Device Type" "R402H16"
			(at 0.064008 -5.517896 90)
			(unlocked yes)
			(layer "F.Fab")
			(hide yes)
			(effects
				(font
					(size 1.016 1.016)
					(thickness 0.1524)
				)
			)
		)
		(duplicate_pad_numbers_are_jumpers no)
		(fp_line
			(start 0.508 -0.9398)
			(end -0.508 -0.9398)
			(stroke
				(width 0.1524)
				(type default)
			)
			(layer "F.SilkS")
		)
		(fp_line
			(start -0.508 -0.9398)
			(end -0.508 0.9398)
			(stroke
				(width 0.1524)
				(type default)
			)
			(layer "F.SilkS")
		)
		(fp_rect
			(start -0.508 0.9398)
			(end 0.508 -0.9398)
			(stroke
				(width 0)
				(type default)
			)
			(fill no)
			(layer "F.CrtYd")
		)
		(fp_rect
			(start -0.508 0.9398)
			(end 0.508 -0.9398)
			(stroke
				(width 0)
				(type default)
			)
			(fill no)
			(layer "F.Fab")
		)
		(pad "1" smd custom
			(at 0 -0.4445 90)
			(size 0.1397 0.1397)
			(layers "F.Cu" "F.Mask" "F.Paste")
			(net "P12V")
			(options
				(clearance outline)
				(anchor circle)
			)
			(primitives
				(gr_poly
					(pts
						(arc
							(start -0.1778 -0.2794)
							(mid -0.249642 -0.249642)
							(end -0.2794 -0.1778)
						)
						(arc
							(start -0.2794 0.1778)
							(mid -0.249642 0.249642)
							(end -0.1778 0.2794)
						)
						(arc
							(start 0.1778 0.2794)
							(mid 0.249642 0.249642)
							(end 0.2794 0.1778)
						)
						(arc
							(start 0.2794 -0.1778)
							(mid 0.249642 -0.249642)
							(end 0.1778 -0.2794)
						)
					)
					(width 0)
					(fill yes)
				)
			)
		)
		(pad "2" smd custom
			(at 0 0.4445 90)
			(size 0.1397 0.1397)
			(layers "F.Cu" "F.Mask" "F.Paste")
			(net "SW_HDD6_P")
			(options
				(clearance outline)
				(anchor circle)
			)
			(primitives
				(gr_poly
					(pts
						(arc
							(start -0.1778 -0.2794)
							(mid -0.249642 -0.249642)
							(end -0.2794 -0.1778)
						)
						(arc
							(start -0.2794 0.1778)
							(mid -0.249642 0.249642)
							(end -0.1778 0.2794)
						)
						(arc
							(start 0.1778 0.2794)
							(mid 0.249642 0.249642)
							(end 0.2794 0.1778)
						)
						(arc
							(start 0.2794 -0.1778)
							(mid 0.249642 -0.249642)
							(end 0.1778 -0.2794)
						)
					)
					(width 0)
					(fill yes)
				)
			)
		)
	)
	(footprint ""
		(layer "F.Cu")
		(at 29.209746 -327.307702 90)
		(property "Reference" "R260"
			(at 0 0 90)
			(layer "F.SilkS")
			(hide yes)
			(effects
				(font
					(size 1.27 1.27)
				)
			)
		)
		(property "Value" "2R2010J-1-GP"
			(at 0.254 -8.0772 90)
			(unlocked yes)
			(layer "F.Fab")
			(hide yes)
			(effects
				(font
					(size 1.016 1.016)
					(thickness 0.1524)
				)
			)
		)
		(property "Device Type" "R2010H28"
			(at 0.254 -9.6774 90)
			(unlocked yes)
			(layer "F.Fab")
			(hide yes)
			(effects
				(font
					(size 1.016 1.016)
					(thickness 0.1524)
				)
			)
		)
		(duplicate_pad_numbers_are_jumpers no)
		(fp_line
			(start 1.651 -3.302)
			(end -1.651 -3.302)
			(stroke
				(width 0.1524)
				(type default)
			)
			(layer "F.SilkS")
		)
		(fp_line
			(start -1.651 -3.302)
			(end -1.651 3.302)
			(stroke
				(width 0.1524)
				(type default)
			)
			(layer "F.SilkS")
		)
		(fp_line
			(start 1.651 3.302)
			(end 1.651 -3.302)
			(stroke
				(width 0.1524)
				(type default)
			)
			(layer "F.SilkS")
		)
		(fp_line
			(start -1.651 3.302)
			(end 1.651 3.302)
			(stroke
				(width 0.1524)
				(type default)
			)
			(layer "F.SilkS")
		)
		(fp_rect
			(start -1.7272 -3.3782)
			(end 1.7272 3.3782)
			(stroke
				(width 0)
				(type default)
			)
			(fill no)
			(layer "F.CrtYd")
		)
		(fp_poly
			(pts
				(xy 1.7272 3.3782) (xy 1.7272 -3.3782) (xy -1.7272 -3.3782) (xy -1.7272 3.3782)
			)
			(stroke
				(width 0)
				(type default)
			)
			(fill no)
			(layer "F.Fab")
		)
		(pad "1" smd rect
			(at 0 -2.3495 90)
			(size 2.794 1.143)
			(layers "F.Cu" "F.Mask" "F.Paste")
			(net "5V_PRE_11")
		)
		(pad "2" smd rect
			(at 0 2.3495 90)
			(size 2.794 1.143)
			(layers "F.Cu" "F.Mask" "F.Paste")
			(net "P5V_HDD11")
		)
	)
	(footprint ""
		(layer "F.Cu")
		(at 75.401932 -494.240312 180)
		(property "Reference" "C187"
			(at 0 0 180)
			(layer "F.SilkS")
			(hide yes)
			(effects
				(font
					(size 1.27 1.27)
				)
			)
		)
		(property "Value" "SCD1U10V2KX-5GP"
			(at 1.1811 -2.7051 180)
			(unlocked yes)
			(layer "F.Fab")
			(hide yes)
			(effects
				(font
					(size 1.016 1.016)
					(thickness 0.1524)
				)
			)
		)
		(property "Device Type" "C402H22"
			(at 1.1811 -4.2291 180)
			(unlocked yes)
			(layer "F.Fab")
			(hide yes)
			(effects
				(font
					(size 1.016 1.016)
					(thickness 0.1524)
				)
			)
		)
		(duplicate_pad_numbers_are_jumpers no)
		(fp_rect
			(start -0.4318 0.9525)
			(end 0.4318 -0.9525)
			(stroke
				(width 0)
				(type default)
			)
			(fill no)
			(layer "F.CrtYd")
		)
		(fp_rect
			(start -0.4318 0.9525)
			(end 0.4318 -0.9525)
			(stroke
				(width 0)
				(type default)
			)
			(fill no)
			(layer "F.Fab")
		)
		(pad "1" smd custom
			(at 0 -0.4445 180)
			(size 0.1524 0.1524)
			(layers "F.Cu" "F.Mask" "F.Paste")
			(net "P3V3")
			(options
				(clearance outline)
				(anchor circle)
			)
			(primitives
				(gr_poly
					(pts
						(arc
							(start 0.3048 -0.2032)
							(mid 0.275042 -0.275042)
							(end 0.2032 -0.3048)
						)
						(arc
							(start -0.2032 -0.3048)
							(mid -0.275042 -0.275042)
							(end -0.3048 -0.2032)
						)
						(arc
							(start -0.3048 0.2032)
							(mid -0.275042 0.275042)
							(end -0.2032 0.3048)
						)
						(arc
							(start 0.2032 0.3048)
							(mid 0.275042 0.275042)
							(end 0.3048 0.2032)
						)
					)
					(width 0)
					(fill yes)
				)
			)
		)
		(pad "2" smd custom
			(at 0 0.4445 180)
			(size 0.1524 0.1524)
			(layers "F.Cu" "F.Mask" "F.Paste")
			(net "GND")
			(options
				(clearance outline)
				(anchor circle)
			)
			(primitives
				(gr_poly
					(pts
						(arc
							(start 0.3048 -0.2032)
							(mid 0.275042 -0.275042)
							(end 0.2032 -0.3048)
						)
						(arc
							(start -0.2032 -0.3048)
							(mid -0.275042 -0.275042)
							(end -0.3048 -0.2032)
						)
						(arc
							(start -0.3048 0.2032)
							(mid -0.275042 0.275042)
							(end -0.2032 0.3048)
						)
						(arc
							(start 0.2032 0.3048)
							(mid 0.275042 0.275042)
							(end 0.3048 0.2032)
						)
					)
					(width 0)
					(fill yes)
				)
			)
		)
	)
)
